(kicad_pcb
	(version 20260206)
	(generator "pcbnew")
	(generator_version "10.0")
	(general
		(thickness 1.6)
		(legacy_teardrops no)
	)
	(paper "A4")
	(title_block
		(title "01162023_DA0F0TEBIF0_F0T_Expander_BD_F_brd_V02_OCP.brd")
		(comment 1 "Grand Teton / footprints 5766-5773 of 9728")
	)
	(layers
		(0 "F.Cu" signal "TOP")
		(4 "In1.Cu" signal "GND")
		(6 "In2.Cu" signal "VCC")
		(8 "In3.Cu" signal "VCC1")
		(10 "In4.Cu" signal "GND1")
		(12 "In5.Cu" signal "IN1")
		(14 "In6.Cu" signal "GND2")
		(16 "In7.Cu" signal "IN2")
		(18 "In8.Cu" signal "GND3")
		(20 "In9.Cu" signal "IN3")
		(22 "In10.Cu" signal "GND4")
		(24 "In11.Cu" signal "IN4")
		(26 "In12.Cu" signal "GND5")
		(28 "In13.Cu" signal "IN5")
		(30 "In14.Cu" signal "GND6")
		(32 "In15.Cu" signal "IN6")
		(34 "In16.Cu" signal "GND7")
		(2 "B.Cu" signal "BOTTOM")
		(9 "F.Adhes" user "F.Adhesive")
		(11 "B.Adhes" user "B.Adhesive")
		(13 "F.Paste" user "Package Geometry/Pastemask Top")
		(15 "B.Paste" user "Package Geometry/Pastemask Bottom")
		(5 "F.SilkS" user "Ref Des/Silkscreen Top")
		(7 "B.SilkS" user "Ref Des/Silkscreen Bottom")
		(1 "F.Mask" user "Board Geometry/Soldermask Top")
		(3 "B.Mask" user "Board Geometry/Soldermask Bottom")
		(17 "Dwgs.User" user "User.Drawings")
		(19 "Cmts.User" user "User.Comments")
		(21 "Eco1.User" user "User.Eco1")
		(23 "Eco2.User" user "User.Eco2")
		(25 "Edge.Cuts" user "Board Geometry/Outline")
		(27 "Margin" user)
		(31 "F.CrtYd" user "Package Geometry/Place Bound Top")
		(29 "B.CrtYd" user "Package Geometry/Place Bound Bottom")
		(35 "F.Fab" user "Ref Des/Assembly Top")
		(33 "B.Fab" user "Ref Des/Assembly Bottom")
	)
	(footprint ""
		(layer "F.Cu")
		(at 455.339196 -319.515998 180)
		(property "Reference" "PC264"
			(at 0 0 180)
			(layer "F.SilkS")
			(hide yes)
			(effects
				(font
					(size 1.27 1.27)
				)
			)
		)
		(property "Value" ""
			(at 0 0 180)
			(layer "F.Fab")
			(effects
				(font
					(size 1.27 1.27)
				)
			)
		)
		(duplicate_pad_numbers_are_jumpers no)
		(fp_line
			(start 0.7874 0.4064)
			(end -0.7874 0.4064)
			(stroke
				(width 0.1524)
				(type default)
			)
			(layer "F.SilkS")
		)
		(fp_line
			(start 0.7874 -0.4064)
			(end 0.7874 0.4064)
			(stroke
				(width 0.1524)
				(type default)
			)
			(layer "F.SilkS")
		)
		(fp_line
			(start -0.7874 0.4064)
			(end -0.7874 -0.4064)
			(stroke
				(width 0.1524)
				(type default)
			)
			(layer "F.SilkS")
		)
		(fp_line
			(start -0.7874 -0.4064)
			(end 0.7874 -0.4064)
			(stroke
				(width 0.1524)
				(type default)
			)
			(layer "F.SilkS")
		)
		(fp_line
			(start 0.67945 0.3048)
			(end 0.120396 0.3048)
			(stroke
				(width 0.1)
				(type default)
			)
			(layer "F.Fab")
		)
		(fp_line
			(start 0.67945 -0.3048)
			(end 0.67945 0.3048)
			(stroke
				(width 0.1)
				(type default)
			)
			(layer "F.Fab")
		)
		(fp_line
			(start 0.12065 -0.2794)
			(end 0.12065 -0.3048)
			(stroke
				(width 0.1)
				(type default)
			)
			(layer "F.Fab")
		)
		(fp_line
			(start 0.12065 -0.3048)
			(end 0.67945 -0.3048)
			(stroke
				(width 0.1)
				(type default)
			)
			(layer "F.Fab")
		)
		(fp_line
			(start 0.120396 0.3048)
			(end 0.120396 0.2794)
			(stroke
				(width 0.1)
				(type default)
			)
			(layer "F.Fab")
		)
		(fp_line
			(start 0.120396 0.2794)
			(end -0.12065 0.2794)
			(stroke
				(width 0.1)
				(type default)
			)
			(layer "F.Fab")
		)
		(fp_line
			(start -0.12065 0.3048)
			(end -0.67945 0.3048)
			(stroke
				(width 0.1)
				(type default)
			)
			(layer "F.Fab")
		)
		(fp_line
			(start -0.12065 0.2794)
			(end -0.12065 0.3048)
			(stroke
				(width 0.1)
				(type default)
			)
			(layer "F.Fab")
		)
		(fp_line
			(start -0.12065 -0.2794)
			(end 0.12065 -0.2794)
			(stroke
				(width 0.1)
				(type default)
			)
			(layer "F.Fab")
		)
		(fp_line
			(start -0.12065 -0.305054)
			(end -0.12065 -0.2794)
			(stroke
				(width 0.1)
				(type default)
			)
			(layer "F.Fab")
		)
		(fp_line
			(start -0.67945 0.3048)
			(end -0.67945 -0.305054)
			(stroke
				(width 0.1)
				(type default)
			)
			(layer "F.Fab")
		)
		(fp_line
			(start -0.67945 -0.305054)
			(end -0.12065 -0.305054)
			(stroke
				(width 0.1)
				(type default)
			)
			(layer "F.Fab")
		)
		(pad "1" smd circle
			(at -0.40005 0 180)
			(size 0 0)
			(layers "F.Cu" "F.Mask" "F.Paste")
			(net "P12V_AUX")
		)
		(pad "2" smd circle
			(at 0.40005 0 180)
			(size 0 0)
			(layers "F.Cu" "F.Mask" "F.Paste")
			(net "GND")
		)
	)
	(footprint ""
		(layer "F.Cu")
		(at 98.965258 -223.21774 90)
		(property "Reference" "PJ17"
			(at 0 0 90)
			(layer "F.SilkS")
			(hide yes)
			(effects
				(font
					(size 1.27 1.27)
				)
			)
		)
		(property "Value" ""
			(at 0 0 90)
			(layer "F.Fab")
			(effects
				(font
					(size 1.27 1.27)
				)
			)
		)
		(duplicate_pad_numbers_are_jumpers no)
		(pad "1" smd circle
			(at -0.7493 0 180)
			(size 0 0)
			(layers "F.Cu" "F.Mask" "F.Paste")
			(net "SH_P1V8_PEX_FB")
		)
		(pad "2" smd rect
			(at 0.7493 0)
			(size 0.7112 0.8128)
			(layers "F.Cu" "F.Mask" "F.Paste")
			(net "P1V8_PEX_R")
		)
		(zone
			(layer "F.Cu")
			(hatch none 0.5)
			(connect_pads
				(clearance 0)
			)
			(min_thickness 0.25)
			(keepout
				(tracks allowed)
				(vias not_allowed)
				(pads allowed)
				(copperpour not_allowed)
				(footprints allowed)
			)
			(placement
				(enabled no)
				(sheetname "")
			)
			(fill
				(thermal_gap 0.5)
				(thermal_bridge_width 0.5)
				(island_removal_mode 0)
			)
			(polygon
				(pts
					(xy 98.558858 -224.42424) (xy 98.558858 -222.03664) (xy 99.376484 -222.03664) (xy 99.376484 -224.42424)
				)
			)
		)
	)
	(footprint ""
		(layer "F.Cu")
		(at 438.31764 -304.036476 90)
		(property "Reference" "R1451"
			(at 0 0 90)
			(layer "F.SilkS")
			(hide yes)
			(effects
				(font
					(size 1.27 1.27)
				)
			)
		)
		(property "Value" ""
			(at 0 0 90)
			(layer "F.Fab")
			(effects
				(font
					(size 1.27 1.27)
				)
			)
		)
		(duplicate_pad_numbers_are_jumpers no)
		(fp_line
			(start 0.7874 -0.4064)
			(end 0.7874 0.4064)
			(stroke
				(width 0.1524)
				(type default)
			)
			(layer "F.SilkS")
		)
		(fp_line
			(start -0.7874 -0.4064)
			(end 0.7874 -0.4064)
			(stroke
				(width 0.1524)
				(type default)
			)
			(layer "F.SilkS")
		)
		(fp_line
			(start 0.7874 0.4064)
			(end -0.7874 0.4064)
			(stroke
				(width 0.1524)
				(type default)
			)
			(layer "F.SilkS")
		)
		(fp_line
			(start -0.7874 0.4064)
			(end -0.7874 -0.4064)
			(stroke
				(width 0.1524)
				(type default)
			)
			(layer "F.SilkS")
		)
		(fp_line
			(start -0.12065 -0.305054)
			(end -0.12065 -0.2794)
			(stroke
				(width 0.1)
				(type default)
			)
			(layer "F.Fab")
		)
		(fp_line
			(start -0.67945 -0.305054)
			(end -0.12065 -0.305054)
			(stroke
				(width 0.1)
				(type default)
			)
			(layer "F.Fab")
		)
		(fp_line
			(start 0.67945 -0.3048)
			(end 0.67945 0.3048)
			(stroke
				(width 0.1)
				(type default)
			)
			(layer "F.Fab")
		)
		(fp_line
			(start 0.12065 -0.3048)
			(end 0.67945 -0.3048)
			(stroke
				(width 0.1)
				(type default)
			)
			(layer "F.Fab")
		)
		(fp_line
			(start 0.12065 -0.2794)
			(end 0.12065 -0.3048)
			(stroke
				(width 0.1)
				(type default)
			)
			(layer "F.Fab")
		)
		(fp_line
			(start -0.12065 -0.2794)
			(end 0.12065 -0.2794)
			(stroke
				(width 0.1)
				(type default)
			)
			(layer "F.Fab")
		)
		(fp_line
			(start 0.120396 0.2794)
			(end -0.12065 0.2794)
			(stroke
				(width 0.1)
				(type default)
			)
			(layer "F.Fab")
		)
		(fp_line
			(start -0.12065 0.2794)
			(end -0.12065 0.3048)
			(stroke
				(width 0.1)
				(type default)
			)
			(layer "F.Fab")
		)
		(fp_line
			(start 0.67945 0.3048)
			(end 0.120396 0.3048)
			(stroke
				(width 0.1)
				(type default)
			)
			(layer "F.Fab")
		)
		(fp_line
			(start 0.120396 0.3048)
			(end 0.120396 0.2794)
			(stroke
				(width 0.1)
				(type default)
			)
			(layer "F.Fab")
		)
		(fp_line
			(start -0.12065 0.3048)
			(end -0.67945 0.3048)
			(stroke
				(width 0.1)
				(type default)
			)
			(layer "F.Fab")
		)
		(fp_line
			(start -0.67945 0.3048)
			(end -0.67945 -0.305054)
			(stroke
				(width 0.1)
				(type default)
			)
			(layer "F.Fab")
		)
		(pad "1" smd circle
			(at -0.40005 0 90)
			(size 0 0)
			(layers "F.Cu" "F.Mask" "F.Paste")
			(net "GND")
		)
		(pad "2" smd circle
			(at 0.40005 0 90)
			(size 0 0)
			(layers "F.Cu" "F.Mask" "F.Paste")
			(net "PEX3_SPARE3")
		)
	)
	(footprint ""
		(layer "F.Cu")
		(at 11.1379 -264.508234)
		(property "Reference" "L84"
			(at 0 0 0)
			(layer "F.SilkS")
			(hide yes)
			(effects
				(font
					(size 1.27 1.27)
				)
			)
		)
		(property "Value" ""
			(at 0 0 0)
			(layer "F.Fab")
			(effects
				(font
					(size 1.27 1.27)
				)
			)
		)
		(duplicate_pad_numbers_are_jumpers no)
		(fp_line
			(start -2.248154 -4.9911)
			(end -2.248154 -1.786382)
			(stroke
				(width 0.1524)
				(type default)
			)
			(layer "F.SilkS")
		)
		(fp_line
			(start -2.248154 1.859026)
			(end -2.248154 4.9911)
			(stroke
				(width 0.1524)
				(type default)
			)
			(layer "F.SilkS")
		)
		(fp_line
			(start -2.248154 4.9911)
			(end 2.248154 4.9911)
			(stroke
				(width 0.1524)
				(type default)
			)
			(layer "F.SilkS")
		)
		(fp_line
			(start 2.248154 -4.9911)
			(end -2.248154 -4.9911)
			(stroke
				(width 0.1524)
				(type default)
			)
			(layer "F.SilkS")
		)
		(fp_line
			(start 2.248154 -1.775206)
			(end 2.248154 -4.9911)
			(stroke
				(width 0.1524)
				(type default)
			)
			(layer "F.SilkS")
		)
		(fp_line
			(start 2.248154 4.9911)
			(end 2.248154 1.79324)
			(stroke
				(width 0.1524)
				(type default)
			)
			(layer "F.SilkS")
		)
		(fp_line
			(start -1.700022 -0.899922)
			(end -1.700022 0.899922)
			(stroke
				(width 0.1)
				(type default)
			)
			(layer "F.Fab")
		)
		(fp_line
			(start -1.700022 0.899922)
			(end 1.700022 0.899922)
			(stroke
				(width 0.1)
				(type default)
			)
			(layer "F.Fab")
		)
		(fp_line
			(start 1.700022 -0.899922)
			(end -1.700022 -0.899922)
			(stroke
				(width 0.1)
				(type default)
			)
			(layer "F.Fab")
		)
		(fp_line
			(start 1.700022 0.899922)
			(end 1.700022 -0.899922)
			(stroke
				(width 0.1)
				(type default)
			)
			(layer "F.Fab")
		)
		(pad "1" smd rect
			(at -1.575054 0)
			(size 1.1684 9.8044)
			(layers "F.Cu" "F.Mask" "F.Paste")
			(net "P1V25_PEX0")
		)
		(pad "2" smd rect
			(at 1.575054 0)
			(size 1.1684 9.8044)
			(layers "F.Cu" "F.Mask" "F.Paste")
			(net "P1V25_SERDES_VDDPLL_PEX0")
		)
	)
	(footprint ""
		(layer "F.Cu")
		(at 213.730332 -224.398586 180)
		(property "Reference" "R4881"
			(at 0 0 180)
			(layer "F.SilkS")
			(hide yes)
			(effects
				(font
					(size 1.27 1.27)
				)
			)
		)
		(property "Value" ""
			(at 0 0 180)
			(layer "F.Fab")
			(effects
				(font
					(size 1.27 1.27)
				)
			)
		)
		(duplicate_pad_numbers_are_jumpers no)
		(fp_line
			(start 0.7874 0.4064)
			(end -0.7874 0.4064)
			(stroke
				(width 0.1524)
				(type default)
			)
			(layer "F.SilkS")
		)
		(fp_line
			(start 0.7874 -0.4064)
			(end 0.7874 0.4064)
			(stroke
				(width 0.1524)
				(type default)
			)
			(layer "F.SilkS")
		)
		(fp_line
			(start -0.7874 0.4064)
			(end -0.7874 -0.4064)
			(stroke
				(width 0.1524)
				(type default)
			)
			(layer "F.SilkS")
		)
		(fp_line
			(start -0.7874 -0.4064)
			(end 0.7874 -0.4064)
			(stroke
				(width 0.1524)
				(type default)
			)
			(layer "F.SilkS")
		)
		(fp_line
			(start 0.67945 0.3048)
			(end 0.120396 0.3048)
			(stroke
				(width 0.1)
				(type default)
			)
			(layer "F.Fab")
		)
		(fp_line
			(start 0.67945 -0.3048)
			(end 0.67945 0.3048)
			(stroke
				(width 0.1)
				(type default)
			)
			(layer "F.Fab")
		)
		(fp_line
			(start 0.12065 -0.2794)
			(end 0.12065 -0.3048)
			(stroke
				(width 0.1)
				(type default)
			)
			(layer "F.Fab")
		)
		(fp_line
			(start 0.12065 -0.3048)
			(end 0.67945 -0.3048)
			(stroke
				(width 0.1)
				(type default)
			)
			(layer "F.Fab")
		)
		(fp_line
			(start 0.120396 0.3048)
			(end 0.120396 0.2794)
			(stroke
				(width 0.1)
				(type default)
			)
			(layer "F.Fab")
		)
		(fp_line
			(start 0.120396 0.2794)
			(end -0.12065 0.2794)
			(stroke
				(width 0.1)
				(type default)
			)
			(layer "F.Fab")
		)
		(fp_line
			(start -0.12065 0.3048)
			(end -0.67945 0.3048)
			(stroke
				(width 0.1)
				(type default)
			)
			(layer "F.Fab")
		)
		(fp_line
			(start -0.12065 0.2794)
			(end -0.12065 0.3048)
			(stroke
				(width 0.1)
				(type default)
			)
			(layer "F.Fab")
		)
		(fp_line
			(start -0.12065 -0.2794)
			(end 0.12065 -0.2794)
			(stroke
				(width 0.1)
				(type default)
			)
			(layer "F.Fab")
		)
		(fp_line
			(start -0.12065 -0.305054)
			(end -0.12065 -0.2794)
			(stroke
				(width 0.1)
				(type default)
			)
			(layer "F.Fab")
		)
		(fp_line
			(start -0.67945 0.3048)
			(end -0.67945 -0.305054)
			(stroke
				(width 0.1)
				(type default)
			)
			(layer "F.Fab")
		)
		(fp_line
			(start -0.67945 -0.305054)
			(end -0.12065 -0.305054)
			(stroke
				(width 0.1)
				(type default)
			)
			(layer "F.Fab")
		)
		(pad "1" smd circle
			(at -0.40005 0 180)
			(size 0 0)
			(layers "F.Cu" "F.Mask" "F.Paste")
			(net "SMB_MB_I3C_ISO_SCL")
		)
		(pad "2" smd circle
			(at 0.40005 0 180)
			(size 0 0)
			(layers "F.Cu" "F.Mask" "F.Paste")
			(net "P3V3_AUX")
		)
	)
	(footprint ""
		(layer "F.Cu")
		(at 352.319844 -158.417768)
		(property "Reference" "R4809"
			(at 0 0 0)
			(layer "F.SilkS")
			(hide yes)
			(effects
				(font
					(size 1.27 1.27)
				)
			)
		)
		(property "Value" ""
			(at 0 0 0)
			(layer "F.Fab")
			(effects
				(font
					(size 1.27 1.27)
				)
			)
		)
		(duplicate_pad_numbers_are_jumpers no)
		(fp_line
			(start -0.7874 -0.4064)
			(end 0.7874 -0.4064)
			(stroke
				(width 0.1524)
				(type default)
			)
			(layer "F.SilkS")
		)
		(fp_line
			(start -0.7874 0.4064)
			(end -0.7874 -0.4064)
			(stroke
				(width 0.1524)
				(type default)
			)
			(layer "F.SilkS")
		)
		(fp_line
			(start 0.7874 -0.4064)
			(end 0.7874 0.4064)
			(stroke
				(width 0.1524)
				(type default)
			)
			(layer "F.SilkS")
		)
		(fp_line
			(start 0.7874 0.4064)
			(end -0.7874 0.4064)
			(stroke
				(width 0.1524)
				(type default)
			)
			(layer "F.SilkS")
		)
		(fp_line
			(start -0.67945 -0.305054)
			(end -0.12065 -0.305054)
			(stroke
				(width 0.1)
				(type default)
			)
			(layer "F.Fab")
		)
		(fp_line
			(start -0.67945 0.3048)
			(end -0.67945 -0.305054)
			(stroke
				(width 0.1)
				(type default)
			)
			(layer "F.Fab")
		)
		(fp_line
			(start -0.12065 -0.305054)
			(end -0.12065 -0.2794)
			(stroke
				(width 0.1)
				(type default)
			)
			(layer "F.Fab")
		)
		(fp_line
			(start -0.12065 -0.2794)
			(end 0.12065 -0.2794)
			(stroke
				(width 0.1)
				(type default)
			)
			(layer "F.Fab")
		)
		(fp_line
			(start -0.12065 0.2794)
			(end -0.12065 0.3048)
			(stroke
				(width 0.1)
				(type default)
			)
			(layer "F.Fab")
		)
		(fp_line
			(start -0.12065 0.3048)
			(end -0.67945 0.3048)
			(stroke
				(width 0.1)
				(type default)
			)
			(layer "F.Fab")
		)
		(fp_line
			(start 0.120396 0.2794)
			(end -0.12065 0.2794)
			(stroke
				(width 0.1)
				(type default)
			)
			(layer "F.Fab")
		)
		(fp_line
			(start 0.120396 0.3048)
			(end 0.120396 0.2794)
			(stroke
				(width 0.1)
				(type default)
			)
			(layer "F.Fab")
		)
		(fp_line
			(start 0.12065 -0.3048)
			(end 0.67945 -0.3048)
			(stroke
				(width 0.1)
				(type default)
			)
			(layer "F.Fab")
		)
		(fp_line
			(start 0.12065 -0.2794)
			(end 0.12065 -0.3048)
			(stroke
				(width 0.1)
				(type default)
			)
			(layer "F.Fab")
		)
		(fp_line
			(start 0.67945 -0.3048)
			(end 0.67945 0.3048)
			(stroke
				(width 0.1)
				(type default)
			)
			(layer "F.Fab")
		)
		(fp_line
			(start 0.67945 0.3048)
			(end 0.120396 0.3048)
			(stroke
				(width 0.1)
				(type default)
			)
			(layer "F.Fab")
		)
		(pad "1" smd circle
			(at -0.40005 0)
			(size 0 0)
			(layers "F.Cu" "F.Mask" "F.Paste")
			(net "PCA9555_0_PEX3_A0")
		)
		(pad "2" smd circle
			(at 0.40005 0)
			(size 0 0)
			(layers "F.Cu" "F.Mask" "F.Paste")
			(net "P3V3_AUX")
		)
	)
	(footprint ""
		(layer "F.Cu")
		(at 428.319438 -134.394702 180)
		(property "Reference" "C652"
			(at 0 0 180)
			(layer "F.SilkS")
			(hide yes)
			(effects
				(font
					(size 1.27 1.27)
				)
			)
		)
		(property "Value" ""
			(at 0 0 180)
			(layer "F.Fab")
			(effects
				(font
					(size 1.27 1.27)
				)
			)
		)
		(duplicate_pad_numbers_are_jumpers no)
		(fp_line
			(start 0.299974 0.150114)
			(end -0.299974 0.150114)
			(stroke
				(width 0.1)
				(type default)
			)
			(layer "F.Fab")
		)
		(fp_line
			(start 0.299974 -0.150114)
			(end 0.299974 0.150114)
			(stroke
				(width 0.1)
				(type default)
			)
			(layer "F.Fab")
		)
		(fp_line
			(start -0.299974 0.150114)
			(end -0.299974 -0.150114)
			(stroke
				(width 0.1)
				(type default)
			)
			(layer "F.Fab")
		)
		(fp_line
			(start -0.299974 -0.150114)
			(end 0.299974 -0.150114)
			(stroke
				(width 0.1)
				(type default)
			)
			(layer "F.Fab")
		)
		(pad "1" smd rect
			(at -0.2667 0 180)
			(size 0.3048 0.381)
			(layers "F.Cu" "F.Mask" "F.Paste")
			(net "P5E_PEX3_STN0_TX_DP<6>")
		)
		(pad "2" smd rect
			(at 0.2667 0 180)
			(size 0.3048 0.381)
			(layers "F.Cu" "F.Mask" "F.Paste")
			(net "P5E_PEX3_STN0_TX_C_DP<6>")
		)
	)
	(footprint ""
		(layer "F.Cu")
		(at 331.405992 -113.114582 -90)
		(property "Reference" "PD95"
			(at 4.199382 -2.198878 90)
			(unlocked yes)
			(layer "F.SilkS")
			(effects
				(font
					(size 0.7874 0.5842)
					(thickness 0.1524)
				)
				(justify left)
			)
		)
		(property "Value" ""
			(at 0 0 270)
			(layer "F.Fab")
			(effects
				(font
					(size 1.27 1.27)
				)
			)
		)
		(duplicate_pad_numbers_are_jumpers no)
		(fp_line
			(start -3.400044 1.459992)
			(end -3.400044 -1.459992)
			(stroke
				(width 0.1524)
				(type default)
			)
			(layer "F.SilkS")
		)
		(fp_line
			(start 4.107942 1.459992)
			(end -3.400044 1.459992)
			(stroke
				(width 0.1524)
				(type default)
			)
			(layer "F.SilkS")
		)
		(fp_line
			(start -3.400044 -1.459992)
			(end 4.107942 -1.459992)
			(stroke
				(width 0.1524)
				(type default)
			)
			(layer "F.SilkS")
		)
		(fp_line
			(start 4.107942 -1.459992)
			(end 4.107942 1.459992)
			(stroke
				(width 0.1524)
				(type default)
			)
			(layer "F.SilkS")
		)
		(fp_rect
			(start 4.107942 1.459992)
			(end 3.308096 -1.459992)
			(stroke
				(width 0)
				(type default)
			)
			(fill yes)
			(layer "F.SilkS")
		)
		(fp_line
			(start -2.29997 1.459992)
			(end -2.29997 -1.459992)
			(stroke
				(width 0.1)
				(type default)
			)
			(layer "F.Fab")
		)
		(fp_line
			(start 2.29997 1.459992)
			(end -2.29997 1.459992)
			(stroke
				(width 0.1)
				(type default)
			)
			(layer "F.Fab")
		)
		(fp_line
			(start -2.29997 -1.459992)
			(end 2.29997 -1.459992)
			(stroke
				(width 0.1)
				(type default)
			)
			(layer "F.Fab")
		)
		(fp_line
			(start 2.29997 -1.459992)
			(end 2.29997 1.459992)
			(stroke
				(width 0.1)
				(type default)
			)
			(layer "F.Fab")
		)
		(fp_text user "-"
			(at 5.4102 0.29845 90)
			(unlocked yes)
			(layer "F.SilkS")
			(effects
				(font
					(size 1.905 1.4224)
					(thickness 0.1524)
				)
				(justify left)
			)
		)
		(fp_text user "+"
			(at -4.7752 -0.12065 270)
			(unlocked yes)
			(layer "F.SilkS")
			(effects
				(font
					(size 1.905 1.4224)
					(thickness 0.1524)
				)
				(justify left)
			)
		)
		(fp_text user "-"
			(at 5.4102 0.29845 90)
			(unlocked yes)
			(layer "F.Fab")
			(effects
				(font
					(size 1.905 1.4224)
					(thickness 0.1524)
				)
				(justify left)
			)
		)
		(fp_text user "+"
			(at -4.7752 -0.12065 270)
			(unlocked yes)
			(layer "F.Fab")
			(effects
				(font
					(size 1.905 1.4224)
					(thickness 0.1524)
				)
				(justify left)
			)
		)
		(pad "A" smd rect
			(at -1.999996 0)
			(size 1.7018 2.5146)
			(layers "F.Cu" "F.Mask" "F.Paste")
			(net "GND")
		)
		(pad "C" smd rect
			(at 1.999996 0)
			(size 1.7018 2.5146)
			(layers "F.Cu" "F.Mask" "F.Paste")
			(net "P12V_NIC5_R")
		)
	)
)
